(kicad_pcb
	(version 20241229)
	(generator "pcbnew")
	(generator_version "9.0")
	(general
		(thickness 1.292)
		(legacy_teardrops no)
	)
	(paper "A4")
	(title_block
		(title "LPDDR5 Testbed")
		(date "2023-12-19")
		(rev "1.0.0")
		(comment 9 "footprints 144-149 of 160")
	)
	(layers
		(0 "F.Cu" signal)
		(4 "In1.Cu" power)
		(6 "In2.Cu" power)
		(8 "In3.Cu" signal)
		(10 "In4.Cu" signal)
		(2 "B.Cu" signal)
		(9 "F.Adhes" user "F.Adhesive")
		(11 "B.Adhes" user "B.Adhesive")
		(13 "F.Paste" user)
		(15 "B.Paste" user)
		(5 "F.SilkS" user "F.Silkscreen")
		(7 "B.SilkS" user "B.Silkscreen")
		(1 "F.Mask" user)
		(3 "B.Mask" user)
		(17 "Dwgs.User" user "User.Drawings")
		(19 "Cmts.User" user "User.Comments")
		(21 "Eco1.User" user "User.Eco1")
		(23 "Eco2.User" user "User.Eco2")
		(25 "Edge.Cuts" user)
		(27 "Margin" user)
		(31 "F.CrtYd" user "F.Courtyard")
		(29 "B.CrtYd" user "B.Courtyard")
		(35 "F.Fab" user)
		(33 "B.Fab" user)
	)
	(footprint "antmicro-footprints:R_Array_4x0402_Panasonic_EXB28V"
		(layer "B.Cu")
		(at 144.2 93.8 180)
		(property "Reference" "R60"
			(at -1.301 1.45 0)
			(unlocked yes)
			(layer "B.SilkS")
			(effects
				(font
					(size 0.7 0.7)
					(thickness 0.15)
				)
				(justify left bottom mirror)
			)
		)
		(property "Value" "R_4x100R_0402_array"
			(at -1.5 -2 0)
			(layer "B.Fab")
			(effects
				(font
					(size 0.7 0.7)
					(thickness 0.15)
				)
				(justify left bottom mirror)
			)
		)
		(property "Author" "Antmicro"
			(at 288.4 187.6 0)
			(layer "B.Fab")
			(hide yes)
			(effects
				(font
					(size 1 1)
					(thickness 0.15)
				)
				(justify mirror)
			)
		)
		(property "License" "Apache-2.0"
			(at 288.4 187.6 0)
			(layer "B.Fab")
			(hide yes)
			(effects
				(font
					(size 1 1)
					(thickness 0.15)
				)
				(justify mirror)
			)
		)
		(property "MPN" "EXB-28V101JX"
			(at 288.4 187.6 0)
			(layer "B.Fab")
			(hide yes)
			(effects
				(font
					(size 1 1)
					(thickness 0.15)
				)
				(justify mirror)
			)
		)
		(property "Manufacturer" "Panasonic"
			(at 288.4 187.6 0)
			(layer "B.Fab")
			(hide yes)
			(effects
				(font
					(size 1 1)
					(thickness 0.15)
				)
				(justify mirror)
			)
		)
		(property "Val" "R_4x100R_0402"
			(at 288.4 187.6 0)
			(layer "B.Fab")
			(hide yes)
			(effects
				(font
					(size 1 1)
					(thickness 0.15)
				)
				(justify mirror)
			)
		)
		(sheetname "Translators1")
		(sheetfile "translators.kicad_sch")
		(attr smd)
		(fp_line
			(start 1.25 -0.499)
			(end 1.25 0.499)
			(stroke
				(width 0.15)
				(type solid)
			)
			(layer "B.SilkS")
		)
		(fp_line
			(start -1.25 0.5)
			(end -1.25 -0.498)
			(stroke
				(width 0.15)
				(type solid)
			)
			(layer "B.SilkS")
		)
		(fp_rect
			(start -1.25 0.8)
			(end 1.25 -0.8)
			(stroke
				(width 0.05)
				(type solid)
			)
			(fill no)
			(layer "B.CrtYd")
		)
		(fp_line
			(start 0.998 0.5)
			(end 0.998 -0.498)
			(stroke
				(width 0.15)
				(type solid)
			)
			(layer "B.Fab")
		)
		(fp_line
			(start 0.998 -0.498)
			(end -1 -0.498)
			(stroke
				(width 0.15)
				(type solid)
			)
			(layer "B.Fab")
		)
		(fp_line
			(start -1 0.5)
			(end 0.998 0.5)
			(stroke
				(width 0.15)
				(type solid)
			)
			(layer "B.Fab")
		)
		(fp_line
			(start -1 -0.498)
			(end -1 0.5)
			(stroke
				(width 0.15)
				(type solid)
			)
			(layer "B.Fab")
		)
		(pad "1" smd roundrect
			(at -0.8875 -0.45 180)
			(size 0.525 0.5)
			(layers "B.Cu" "B.Mask" "B.Paste")
			(roundrect_rratio 0.25)
			(net 147 "/SODIMM/LPDDR5_IN_B.CS0")
			(pinfunction "R1.1")
			(pintype "passive")
		)
		(pad "2" smd roundrect
			(at -0.25 -0.45 180)
			(size 0.25 0.5)
			(layers "B.Cu" "B.Mask" "B.Paste")
			(roundrect_rratio 0.25)
			(net 144 "/SODIMM/LPDDR5_IN_B.CS1")
			(pinfunction "R2.1")
			(pintype "passive")
		)
		(pad "3" smd roundrect
			(at 0.25 -0.45 180)
			(size 0.25 0.5)
			(layers "B.Cu" "B.Mask" "B.Paste")
			(roundrect_rratio 0.25)
			(net 145 "/SODIMM/LPDDR5_IN_B.CA0")
			(pinfunction "R3.1")
			(pintype "passive")
		)
		(pad "4" smd roundrect
			(at 0.8875 -0.45 180)
			(size 0.525 0.5)
			(layers "B.Cu" "B.Mask" "B.Paste")
			(roundrect_rratio 0.25)
			(net 146 "/SODIMM/LPDDR5_IN_B.CA1")
			(pinfunction "R4.1")
			(pintype "passive")
		)
		(pad "5" smd roundrect
			(at 0.8875 0.45 180)
			(size 0.525 0.5)
			(layers "B.Cu" "B.Mask" "B.Paste")
			(roundrect_rratio 0.25)
			(net 103 "/LPDDR5/LPDDR5_B.CA1")
			(pinfunction "R4.2")
			(pintype "passive")
		)
		(pad "6" smd roundrect
			(at 0.25 0.45 180)
			(size 0.25 0.5)
			(layers "B.Cu" "B.Mask" "B.Paste")
			(roundrect_rratio 0.25)
			(net 102 "/LPDDR5/LPDDR5_B.CA0")
			(pinfunction "R3.2")
			(pintype "passive")
		)
		(pad "7" smd roundrect
			(at -0.25 0.45 180)
			(size 0.25 0.5)
			(layers "B.Cu" "B.Mask" "B.Paste")
			(roundrect_rratio 0.25)
			(net 107 "/LPDDR5/LPDDR5_B.CS1")
			(pinfunction "R2.2")
			(pintype "passive")
		)
		(pad "8" smd roundrect
			(at -0.8875 0.45 180)
			(size 0.525 0.5)
			(layers "B.Cu" "B.Mask" "B.Paste")
			(roundrect_rratio 0.25)
			(net 106 "/LPDDR5/LPDDR5_B.CS0")
			(pinfunction "R1.2")
			(pintype "passive")
		)
	)
	(footprint "antmicro-footprints:C_0402_1005Metric"
		(layer "B.Cu")
		(at 138.775 78.45 180)
		(descr "Capacitor SMD 0402")
		(tags "capacitor SMD 0402")
		(property "Reference" "C66"
			(at 1.375 0.65 0)
			(unlocked yes)
			(layer "B.SilkS")
			(effects
				(font
					(size 0.7 0.7)
					(thickness 0.15)
				)
				(justify left bottom mirror)
			)
		)
		(property "Value" "C_4u7_0402"
			(at -1.022927 -2.155213 0)
			(layer "B.Fab")
			(effects
				(font
					(size 0.7 0.7)
					(thickness 0.15)
				)
				(justify left bottom mirror)
			)
		)
		(property "Author" "Antmicro"
			(at 277.55 156.9 0)
			(layer "B.Fab")
			(hide yes)
			(effects
				(font
					(size 1 1)
					(thickness 0.15)
				)
				(justify mirror)
			)
		)
		(property "Dielectric" ""
			(at 277.55 156.9 0)
			(layer "B.Fab")
			(hide yes)
			(effects
				(font
					(size 1 1)
					(thickness 0.15)
				)
				(justify mirror)
			)
		)
		(property "License" "Apache-2.0"
			(at 277.55 156.9 0)
			(layer "B.Fab")
			(hide yes)
			(effects
				(font
					(size 1 1)
					(thickness 0.15)
				)
				(justify mirror)
			)
		)
		(property "MPN" "GRM155R61A475MEAAD"
			(at 277.55 156.9 0)
			(layer "B.Fab")
			(hide yes)
			(effects
				(font
					(size 1 1)
					(thickness 0.15)
				)
				(justify mirror)
			)
		)
		(property "Manufacturer" "Murata"
			(at 277.55 156.9 0)
			(layer "B.Fab")
			(hide yes)
			(effects
				(font
					(size 1 1)
					(thickness 0.15)
				)
				(justify mirror)
			)
		)
		(property "Val" "4u7"
			(at 277.55 156.9 0)
			(layer "B.Fab")
			(hide yes)
			(effects
				(font
					(size 1 1)
					(thickness 0.15)
				)
				(justify mirror)
			)
		)
		(property "Voltage" ""
			(at 277.55 156.9 0)
			(layer "B.Fab")
			(hide yes)
			(effects
				(font
					(size 1 1)
					(thickness 0.15)
				)
				(justify mirror)
			)
		)
		(sheetname "LPDDR5")
		(sheetfile "lpddr5.kicad_sch")
		(attr smd)
		(fp_rect
			(start -0.9659 0.481258)
			(end 0.9649 -0.458742)
			(stroke
				(width 0.05)
				(type solid)
			)
			(fill no)
			(layer "B.CrtYd")
		)
		(fp_line
			(start 0.499 0.25)
			(end 0.499 -0.248)
			(stroke
				(width 0.15)
				(type solid)
			)
			(layer "B.Fab")
		)
		(fp_line
			(start 0.499 -0.248)
			(end -0.499 -0.248)
			(stroke
				(width 0.15)
				(type solid)
			)
			(layer "B.Fab")
		)
		(fp_line
			(start -0.499 0.25)
			(end 0.499 0.25)
			(stroke
				(width 0.15)
				(type solid)
			)
			(layer "B.Fab")
		)
		(fp_line
			(start -0.499 -0.248)
			(end -0.499 0.25)
			(stroke
				(width 0.15)
				(type solid)
			)
			(layer "B.Fab")
		)
		(pad "1" smd roundrect
			(at -0.484 0 180)
			(size 0.59 0.64)
			(layers "B.Cu" "B.Mask" "B.Paste")
			(roundrect_rratio 0.25)
			(net 14 "GND")
			(pintype "passive")
		)
		(pad "2" smd roundrect
			(at 0.484 0 180)
			(size 0.59 0.64)
			(layers "B.Cu" "B.Mask" "B.Paste")
			(roundrect_rratio 0.25)
			(net 13 "+1V05")
			(pintype "passive")
		)
	)
	(footprint "antmicro-footprints:R_0402_1005Metric"
		(layer "B.Cu")
		(at 108.08 89.57)
		(descr "Resistor SMD 0402")
		(tags "resistor SMD 0402")
		(property "Reference" "R53"
			(at -0.88 -0.67 0)
			(unlocked yes)
			(layer "B.SilkS")
			(effects
				(font
					(size 0.7 0.7)
					(thickness 0.15)
				)
				(justify right bottom mirror)
			)
		)
		(property "Value" "R_100R_0402"
			(at -1.011843 -1.772047 0)
			(layer "B.Fab")
			(effects
				(font
					(size 0.7 0.7)
					(thickness 0.15)
				)
				(justify right bottom mirror)
			)
		)
		(property "Author" "Antmicro"
			(at 0 0 0)
			(layer "B.Fab")
			(hide yes)
			(effects
				(font
					(size 1 1)
					(thickness 0.15)
				)
				(justify mirror)
			)
		)
		(property "License" "Apache-2.0"
			(at 0 0 0)
			(layer "B.Fab")
			(hide yes)
			(effects
				(font
					(size 1 1)
					(thickness 0.15)
				)
				(justify mirror)
			)
		)
		(property "MPN" "CR0402-FX-1000GLF"
			(at 0 0 0)
			(layer "B.Fab")
			(hide yes)
			(effects
				(font
					(size 1 1)
					(thickness 0.15)
				)
				(justify mirror)
			)
		)
		(property "Manufacturer" "Bourns"
			(at 0 0 0)
			(layer "B.Fab")
			(hide yes)
			(effects
				(font
					(size 1 1)
					(thickness 0.15)
				)
				(justify mirror)
			)
		)
		(property "Tolerance" "1%"
			(at 0 0 0)
			(layer "B.Fab")
			(hide yes)
			(effects
				(font
					(size 1 1)
					(thickness 0.15)
				)
				(justify mirror)
			)
		)
		(property "Val" "100R"
			(at 0 0 0)
			(layer "B.Fab")
			(hide yes)
			(effects
				(font
					(size 1 1)
					(thickness 0.15)
				)
				(justify mirror)
			)
		)
		(sheetname "Translators")
		(sheetfile "translators.kicad_sch")
		(attr smd)
		(fp_rect
			(start -0.93 0.47)
			(end 0.93 -0.47)
			(stroke
				(width 0.05)
				(type solid)
			)
			(fill no)
			(layer "B.CrtYd")
		)
		(fp_rect
			(start -0.5 0.25)
			(end 0.5 -0.25)
			(stroke
				(width 0.15)
				(type solid)
			)
			(fill no)
			(layer "B.Fab")
		)
		(pad "1" smd roundrect
			(at -0.485 0)
			(size 0.59 0.64)
			(layers "B.Cu" "B.Mask" "B.Paste")
			(roundrect_rratio 0.25)
			(net 48 "/LPDDR5/LPDDR5_A.WCK1_P")
			(pintype "passive")
		)
		(pad "2" smd roundrect
			(at 0.485 0)
			(size 0.59 0.64)
			(layers "B.Cu" "B.Mask" "B.Paste")
			(roundrect_rratio 0.25)
			(net 14 "GND")
			(pintype "passive")
		)
	)
	(footprint "antmicro-footprints:R_0402_1005Metric"
		(layer "B.Cu")
		(at 165.4 89.465)
		(descr "Resistor SMD 0402")
		(tags "resistor SMD 0402")
		(property "Reference" "R80"
			(at -1 -0.765 0)
			(unlocked yes)
			(layer "B.SilkS")
			(effects
				(font
					(size 0.7 0.7)
					(thickness 0.15)
				)
				(justify right bottom mirror)
			)
		)
		(property "Value" "R_100R_0402"
			(at -1.011843 -1.772047 0)
			(layer "B.Fab")
			(effects
				(font
					(size 0.7 0.7)
					(thickness 0.15)
				)
				(justify right bottom mirror)
			)
		)
		(property "Author" "Antmicro"
			(at 0 0 0)
			(layer "B.Fab")
			(hide yes)
			(effects
				(font
					(size 1 1)
					(thickness 0.15)
				)
				(justify mirror)
			)
		)
		(property "License" "Apache-2.0"
			(at 0 0 0)
			(layer "B.Fab")
			(hide yes)
			(effects
				(font
					(size 1 1)
					(thickness 0.15)
				)
				(justify mirror)
			)
		)
		(property "MPN" "CR0402-FX-1000GLF"
			(at 0 0 0)
			(layer "B.Fab")
			(hide yes)
			(effects
				(font
					(size 1 1)
					(thickness 0.15)
				)
				(justify mirror)
			)
		)
		(property "Manufacturer" "Bourns"
			(at 0 0 0)
			(layer "B.Fab")
			(hide yes)
			(effects
				(font
					(size 1 1)
					(thickness 0.15)
				)
				(justify mirror)
			)
		)
		(property "Tolerance" "1%"
			(at 0 0 0)
			(layer "B.Fab")
			(hide yes)
			(effects
				(font
					(size 1 1)
					(thickness 0.15)
				)
				(justify mirror)
			)
		)
		(property "Val" "100R"
			(at 0 0 0)
			(layer "B.Fab")
			(hide yes)
			(effects
				(font
					(size 1 1)
					(thickness 0.15)
				)
				(justify mirror)
			)
		)
		(sheetname "Translators1")
		(sheetfile "translators.kicad_sch")
		(attr smd)
		(fp_rect
			(start -0.93 0.47)
			(end 0.93 -0.47)
			(stroke
				(width 0.05)
				(type solid)
			)
			(fill no)
			(layer "B.CrtYd")
		)
		(fp_rect
			(start -0.5 0.25)
			(end 0.5 -0.25)
			(stroke
				(width 0.15)
				(type solid)
			)
			(fill no)
			(layer "B.Fab")
		)
		(pad "1" smd roundrect
			(at -0.485 0)
			(size 0.59 0.64)
			(layers "B.Cu" "B.Mask" "B.Paste")
			(roundrect_rratio 0.25)
			(net 108 "/LPDDR5/LPDDR5_B.WCK0_P")
			(pintype "passive")
		)
		(pad "2" smd roundrect
			(at 0.485 0)
			(size 0.59 0.64)
			(layers "B.Cu" "B.Mask" "B.Paste")
			(roundrect_rratio 0.25)
			(net 14 "GND")
			(pintype "passive")
		)
	)
	(footprint "antmicro-footprints:C_0402_1005Metric"
		(layer "B.Cu")
		(at 130.775 78.45)
		(descr "Capacitor SMD 0402")
		(tags "capacitor SMD 0402")
		(property "Reference" "C54"
			(at -1.275 1.25 0)
			(unlocked yes)
			(layer "B.SilkS")
			(effects
				(font
					(size 0.7 0.7)
					(thickness 0.15)
				)
				(justify right bottom mirror)
			)
		)
		(property "Value" "C_4u7_0402"
			(at -1.022927 -2.155213 0)
			(layer "B.Fab")
			(effects
				(font
					(size 0.7 0.7)
					(thickness 0.15)
				)
				(justify right bottom mirror)
			)
		)
		(property "Author" "Antmicro"
			(at 0 0 0)
			(layer "B.Fab")
			(hide yes)
			(effects
				(font
					(size 1 1)
					(thickness 0.15)
				)
				(justify mirror)
			)
		)
		(property "Dielectric" ""
			(at 0 0 0)
			(layer "B.Fab")
			(hide yes)
			(effects
				(font
					(size 1 1)
					(thickness 0.15)
				)
				(justify mirror)
			)
		)
		(property "License" "Apache-2.0"
			(at 0 0 0)
			(layer "B.Fab")
			(hide yes)
			(effects
				(font
					(size 1 1)
					(thickness 0.15)
				)
				(justify mirror)
			)
		)
		(property "MPN" "GRM155R61A475MEAAD"
			(at 0 0 0)
			(layer "B.Fab")
			(hide yes)
			(effects
				(font
					(size 1 1)
					(thickness 0.15)
				)
				(justify mirror)
			)
		)
		(property "Manufacturer" "Murata"
			(at 0 0 0)
			(layer "B.Fab")
			(hide yes)
			(effects
				(font
					(size 1 1)
					(thickness 0.15)
				)
				(justify mirror)
			)
		)
		(property "Val" "4u7"
			(at 0 0 0)
			(layer "B.Fab")
			(hide yes)
			(effects
				(font
					(size 1 1)
					(thickness 0.15)
				)
				(justify mirror)
			)
		)
		(property "Voltage" ""
			(at 0 0 0)
			(layer "B.Fab")
			(hide yes)
			(effects
				(font
					(size 1 1)
					(thickness 0.15)
				)
				(justify mirror)
			)
		)
		(sheetname "LPDDR5")
		(sheetfile "lpddr5.kicad_sch")
		(attr smd)
		(fp_rect
			(start -0.9659 0.481258)
			(end 0.9649 -0.458742)
			(stroke
				(width 0.05)
				(type solid)
			)
			(fill no)
			(layer "B.CrtYd")
		)
		(fp_line
			(start -0.499 -0.248)
			(end -0.499 0.25)
			(stroke
				(width 0.15)
				(type solid)
			)
			(layer "B.Fab")
		)
		(fp_line
			(start -0.499 0.25)
			(end 0.499 0.25)
			(stroke
				(width 0.15)
				(type solid)
			)
			(layer "B.Fab")
		)
		(fp_line
			(start 0.499 -0.248)
			(end -0.499 -0.248)
			(stroke
				(width 0.15)
				(type solid)
			)
			(layer "B.Fab")
		)
		(fp_line
			(start 0.499 0.25)
			(end 0.499 -0.248)
			(stroke
				(width 0.15)
				(type solid)
			)
			(layer "B.Fab")
		)
		(pad "1" smd roundrect
			(at -0.484 0)
			(size 0.59 0.64)
			(layers "B.Cu" "B.Mask" "B.Paste")
			(roundrect_rratio 0.25)
			(net 14 "GND")
			(pintype "passive")
		)
		(pad "2" smd roundrect
			(at 0.484 0)
			(size 0.59 0.64)
			(layers "B.Cu" "B.Mask" "B.Paste")
			(roundrect_rratio 0.25)
			(net 13 "+1V05")
			(pintype "passive")
		)
	)
	(footprint "antmicro-footprints:R_0402_1005Metric"
		(layer "B.Cu")
		(at 116.68 89.5 180)
		(descr "Resistor SMD 0402")
		(tags "resistor SMD 0402")
		(property "Reference" "R25"
			(at -0.92 0.6 0)
			(unlocked yes)
			(layer "B.SilkS")
			(effects
				(font
					(size 0.7 0.7)
					(thickness 0.15)
				)
				(justify left bottom mirror)
			)
		)
		(property "Value" "R_100R_0402"
			(at -1.011843 -1.772047 0)
			(layer "B.Fab")
			(effects
				(font
					(size 0.7 0.7)
					(thickness 0.15)
				)
				(justify left bottom mirror)
			)
		)
		(property "Author" "Antmicro"
			(at 233.36 179 0)
			(layer "B.Fab")
			(hide yes)
			(effects
				(font
					(size 1 1)
					(thickness 0.15)
				)
				(justify mirror)
			)
		)
		(property "License" "Apache-2.0"
			(at 233.36 179 0)
			(layer "B.Fab")
			(hide yes)
			(effects
				(font
					(size 1 1)
					(thickness 0.15)
				)
				(justify mirror)
			)
		)
		(property "MPN" "CR0402-FX-1000GLF"
			(at 233.36 179 0)
			(layer "B.Fab")
			(hide yes)
			(effects
				(font
					(size 1 1)
					(thickness 0.15)
				)
				(justify mirror)
			)
		)
		(property "Manufacturer" "Bourns"
			(at 233.36 179 0)
			(layer "B.Fab")
			(hide yes)
			(effects
				(font
					(size 1 1)
					(thickness 0.15)
				)
				(justify mirror)
			)
		)
		(property "Tolerance" "1%"
			(at 233.36 179 0)
			(layer "B.Fab")
			(hide yes)
			(effects
				(font
					(size 1 1)
					(thickness 0.15)
				)
				(justify mirror)
			)
		)
		(property "Val" "100R"
			(at 233.36 179 0)
			(layer "B.Fab")
			(hide yes)
			(effects
				(font
					(size 1 1)
					(thickness 0.15)
				)
				(justify mirror)
			)
		)
		(sheetname "Translators")
		(sheetfile "translators.kicad_sch")
		(attr smd)
		(fp_rect
			(start -0.93 0.47)
			(end 0.93 -0.47)
			(stroke
				(width 0.05)
				(type solid)
			)
			(fill no)
			(layer "B.CrtYd")
		)
		(fp_rect
			(start -0.5 0.25)
			(end 0.5 -0.25)
			(stroke
				(width 0.15)
				(type solid)
			)
			(fill no)
			(layer "B.Fab")
		)
		(pad "1" smd roundrect
			(at -0.485 0 180)
			(size 0.59 0.64)
			(layers "B.Cu" "B.Mask" "B.Paste")
			(roundrect_rratio 0.25)
			(net 46 "/LPDDR5/LPDDR5_A.WCK0_N")
			(pintype "passive")
		)
		(pad "2" smd roundrect
			(at 0.485 0 180)
			(size 0.59 0.64)
			(layers "B.Cu" "B.Mask" "B.Paste")
			(roundrect_rratio 0.25)
			(net 14 "GND")
			(pintype "passive")
		)
	)
)
